# S9S_MB_2U (Grand Teton) — schematic netlist excerpt (pin names and nets, part order shuffled) for the footprints in the layout excerpt that follows; sources: Cadence DE-HDL packaged netlist, KiCad conversion of 03242023_DA0F0TMBIJ0_F0T_Motherboard_J_brd_V01_OCP.brd

U273  LM75BD  IC  pkg SO8_1-27_4-9X3-9  page 170
  SDA  = SMB_LM75_3_3V3AUX_SDA_R1
  SCL  = SMB_LM75_3_3V3AUX_SCL_R1
  OS  = FM_LM75_3_ALERT_N
  GND  = GND
  A2  = U273_3_ADD2
  A1  = U273_3_ADD1
  A0  = U273_3_ADD0
  VCC  = P3V3_AUX

R2932  Q_RES  4.7K 5% CHIP  pkg 0402LF  page 149 : A = FM_SWB_PWR_EN_R1_BUF ; B = GND

(kicad_pcb
	(version 20260206)
	(generator "pcbnew")
	(generator_version "10.0")
	(general
		(thickness 1.6)
		(legacy_teardrops no)
	)
	(paper "A4")
	(title_block
		(title "03242023_DA0F0TMBIJ0_F0T_Motherboard_J_brd_V01_OCP.brd")
		(comment 1 "Grand Teton / footprints 4010-4011 of 6105")
	)
	(layers
		(0 "F.Cu" signal "TOP")
		(4 "In1.Cu" signal "GND")
		(6 "In2.Cu" signal "IN1")
		(8 "In3.Cu" signal "GND1")
		(10 "In4.Cu" signal "IN2")
		(12 "In5.Cu" signal "GND2")
		(14 "In6.Cu" signal "IN3")
		(16 "In7.Cu" signal "GND3")
		(18 "In8.Cu" signal "VCC")
		(20 "In9.Cu" signal "VCC1")
		(22 "In10.Cu" signal "GND4")
		(24 "In11.Cu" signal "IN4")
		(26 "In12.Cu" signal "GND5")
		(28 "In13.Cu" signal "IN5")
		(30 "In14.Cu" signal "GND6")
		(32 "In15.Cu" signal "IN6")
		(34 "In16.Cu" signal "GND7")
		(2 "B.Cu" signal "BOTTOM")
		(9 "F.Adhes" user "F.Adhesive")
		(11 "B.Adhes" user "B.Adhesive")
		(13 "F.Paste" user "Package Geometry/Pastemask Top")
		(15 "B.Paste" user "Package Geometry/Pastemask Bottom")
		(5 "F.SilkS" user "Ref Des/Silkscreen Top")
		(7 "B.SilkS" user "Ref Des/Silkscreen Bottom")
		(1 "F.Mask" user "Board Geometry/Soldermask Top")
		(3 "B.Mask" user "Board Geometry/Soldermask Bottom")
		(17 "Dwgs.User" user "User.Drawings")
		(19 "Cmts.User" user "User.Comments")
		(21 "Eco1.User" user "User.Eco1")
		(23 "Eco2.User" user "User.Eco2")
		(25 "Edge.Cuts" user "Board Geometry/Outline")
		(27 "Margin" user)
		(31 "F.CrtYd" user "Package Geometry/Place Bound Top")
		(29 "B.CrtYd" user "Package Geometry/Place Bound Bottom")
		(35 "F.Fab" user "Ref Des/Assembly Top")
		(33 "B.Fab" user "Ref Des/Assembly Bottom")
	)
	(footprint ""
		(layer "F.Cu")
		(at 113.20653 -15.879064)
		(property "Reference" "U273"
			(at -2.57937 -5.227574 0)
			(unlocked yes)
			(layer "F.SilkS")
			(effects
				(font
					(size 0.7874 0.5842)
					(thickness 0.1524)
				)
				(justify left)
			)
		)
		(property "Value" ""
			(at 0 0 0)
			(layer "F.Fab")
			(effects
				(font
					(size 1.27 1.27)
				)
			)
		)
		(duplicate_pad_numbers_are_jumpers no)
		(fp_line
			(start -3.447796 -2.500122)
			(end -3.447796 2.500122)
			(stroke
				(width 0.1524)
				(type default)
			)
			(layer "F.SilkS")
		)
		(fp_line
			(start -3.447796 2.500122)
			(end 3.447796 2.500122)
			(stroke
				(width 0.1524)
				(type default)
			)
			(layer "F.SilkS")
		)
		(fp_line
			(start -1.484122 -2.500122)
			(end -3.447796 -2.500122)
			(stroke
				(width 0.1524)
				(type default)
			)
			(layer "F.SilkS")
		)
		(fp_line
			(start 0 -1.016)
			(end -1.484122 -2.500122)
			(stroke
				(width 0.1524)
				(type default)
			)
			(layer "F.SilkS")
		)
		(fp_line
			(start 1.484122 -2.500122)
			(end 0 -1.016)
			(stroke
				(width 0.1524)
				(type default)
			)
			(layer "F.SilkS")
		)
		(fp_line
			(start 3.447796 -2.500122)
			(end 1.484122 -2.500122)
			(stroke
				(width 0.1524)
				(type default)
			)
			(layer "F.SilkS")
		)
		(fp_line
			(start 3.447796 2.500122)
			(end 3.447796 -2.500122)
			(stroke
				(width 0.1524)
				(type default)
			)
			(layer "F.SilkS")
		)
		(fp_poly
			(pts
				(xy -2.309114 -3.855974) (xy -2.817114 -2.839974) (xy -3.325114 -3.855974)
			)
			(stroke
				(width 0)
				(type default)
			)
			(fill yes)
			(layer "F.SilkS")
		)
		(fp_line
			(start -1.999996 -2.500122)
			(end -1.999996 2.500122)
			(stroke
				(width 0.1)
				(type default)
			)
			(layer "F.Fab")
		)
		(fp_line
			(start -1.999996 2.500122)
			(end 1.999996 2.500122)
			(stroke
				(width 0.1)
				(type default)
			)
			(layer "F.Fab")
		)
		(fp_line
			(start 1.999996 -2.500122)
			(end -1.999996 -2.500122)
			(stroke
				(width 0.1)
				(type default)
			)
			(layer "F.Fab")
		)
		(fp_line
			(start 1.999996 2.500122)
			(end 1.999996 -2.500122)
			(stroke
				(width 0.1)
				(type default)
			)
			(layer "F.Fab")
		)
		(fp_poly
			(pts
				(xy -4.5974 -2.413) (xy -4.5974 -1.397) (xy -3.5814 -1.905)
			)
			(stroke
				(width 0)
				(type default)
			)
			(fill yes)
			(layer "F.Fab")
		)
		(pad "1" smd rect
			(at -2.649982 -1.905 270)
			(size 0.6096 1.3208)
			(layers "F.Cu" "F.Mask" "F.Paste")
			(net "SMB_LM75_3_3V3AUX_SDA_R1")
		)
		(pad "2" smd rect
			(at -2.649982 -0.635 270)
			(size 0.6096 1.3208)
			(layers "F.Cu" "F.Mask" "F.Paste")
			(net "SMB_LM75_3_3V3AUX_SCL_R1")
		)
		(pad "3" smd rect
			(at -2.649982 0.635 270)
			(size 0.6096 1.3208)
			(layers "F.Cu" "F.Mask" "F.Paste")
			(net "FM_LM75_3_ALERT_N")
		)
		(pad "4" smd rect
			(at -2.649982 1.905 270)
			(size 0.6096 1.3208)
			(layers "F.Cu" "F.Mask" "F.Paste")
			(net "GND")
		)
		(pad "5" smd rect
			(at 2.649982 1.905 270)
			(size 0.6096 1.3208)
			(layers "F.Cu" "F.Mask" "F.Paste")
			(net "U273_3_ADD2")
		)
		(pad "6" smd rect
			(at 2.649982 0.635 270)
			(size 0.6096 1.3208)
			(layers "F.Cu" "F.Mask" "F.Paste")
			(net "U273_3_ADD1")
		)
		(pad "7" smd rect
			(at 2.649982 -0.635 270)
			(size 0.6096 1.3208)
			(layers "F.Cu" "F.Mask" "F.Paste")
			(net "U273_3_ADD0")
		)
		(pad "8" smd rect
			(at 2.649982 -1.905 270)
			(size 0.6096 1.3208)
			(layers "F.Cu" "F.Mask" "F.Paste")
			(net "P3V3_AUX")
		)
	)
	(footprint ""
		(layer "F.Cu")
		(at 31.29788 -429.859948)
		(property "Reference" "R2932"
			(at 0 0 0)
			(layer "F.SilkS")
			(hide yes)
			(effects
				(font
					(size 1.27 1.27)
				)
			)
		)
		(property "Value" ""
			(at 0 0 0)
			(layer "F.Fab")
			(effects
				(font
					(size 1.27 1.27)
				)
			)
		)
		(duplicate_pad_numbers_are_jumpers no)
		(fp_line
			(start -0.7874 -0.4064)
			(end 0.7874 -0.4064)
			(stroke
				(width 0.1524)
				(type default)
			)
			(layer "F.SilkS")
		)
		(fp_line
			(start -0.7874 0.4064)
			(end -0.7874 -0.4064)
			(stroke
				(width 0.1524)
				(type default)
			)
			(layer "F.SilkS")
		)
		(fp_line
			(start 0.7874 -0.4064)
			(end 0.7874 0.4064)
			(stroke
				(width 0.1524)
				(type default)
			)
			(layer "F.SilkS")
		)
		(fp_line
			(start 0.7874 0.4064)
			(end -0.7874 0.4064)
			(stroke
				(width 0.1524)
				(type default)
			)
			(layer "F.SilkS")
		)
		(fp_line
			(start -0.67945 -0.305054)
			(end -0.12065 -0.305054)
			(stroke
				(width 0.1)
				(type default)
			)
			(layer "F.Fab")
		)
		(fp_line
			(start -0.67945 0.3048)
			(end -0.67945 -0.305054)
			(stroke
				(width 0.1)
				(type default)
			)
			(layer "F.Fab")
		)
		(fp_line
			(start -0.12065 -0.305054)
			(end -0.12065 -0.2794)
			(stroke
				(width 0.1)
				(type default)
			)
			(layer "F.Fab")
		)
		(fp_line
			(start -0.12065 -0.2794)
			(end 0.12065 -0.2794)
			(stroke
				(width 0.1)
				(type default)
			)
			(layer "F.Fab")
		)
		(fp_line
			(start -0.12065 0.2794)
			(end -0.12065 0.3048)
			(stroke
				(width 0.1)
				(type default)
			)
			(layer "F.Fab")
		)
		(fp_line
			(start -0.12065 0.3048)
			(end -0.67945 0.3048)
			(stroke
				(width 0.1)
				(type default)
			)
			(layer "F.Fab")
		)
		(fp_line
			(start 0.120396 0.2794)
			(end -0.12065 0.2794)
			(stroke
				(width 0.1)
				(type default)
			)
			(layer "F.Fab")
		)
		(fp_line
			(start 0.120396 0.3048)
			(end 0.120396 0.2794)
			(stroke
				(width 0.1)
				(type default)
			)
			(layer "F.Fab")
		)
		(fp_line
			(start 0.12065 -0.3048)
			(end 0.67945 -0.3048)
			(stroke
				(width 0.1)
				(type default)
			)
			(layer "F.Fab")
		)
		(fp_line
			(start 0.12065 -0.2794)
			(end 0.12065 -0.3048)
			(stroke
				(width 0.1)
				(type default)
			)
			(layer "F.Fab")
		)
		(fp_line
			(start 0.67945 -0.3048)
			(end 0.67945 0.3048)
			(stroke
				(width 0.1)
				(type default)
			)
			(layer "F.Fab")
		)
		(fp_line
			(start 0.67945 0.3048)
			(end 0.120396 0.3048)
			(stroke
				(width 0.1)
				(type default)
			)
			(layer "F.Fab")
		)
		(pad "1" smd circle
			(at -0.40005 0)
			(size 0 0)
			(layers "F.Cu" "F.Mask" "F.Paste")
			(net "FM_SWB_PWR_EN_R1_BUF")
		)
		(pad "2" smd circle
			(at 0.40005 0)
			(size 0 0)
			(layers "F.Cu" "F.Mask" "F.Paste")
			(net "GND")
		)
	)
)
